FILE_TYPE = MULTI_PHYS_TABLE;

PART 'LT6700CS61TRPBF'

{========================================================================================}
:VALUE               | PART_TYPE | MATERIAL | PART_NUMBER    = STANDARD        | LIFECYCLE          | PART_NUMBER   | JEDEC_TYPE                | DESCRIPTION                              | MANUFTR | MANUF_PN            | RD_CMPLS_LVL | CMPLS_LVL | FROM_PJ     | CLASS | DIP_SMD | DATA                       | EE_CHECK_LIST | FP_ECN | PSL | CREATOR | STATUS | MSD | ESD_CDM | ESD_HBM | ESD_MM | PIN_LENGTH_SHORT_PIN | PIN_LENGTH_LONG_PIN | CREATEDAY  ;
{========================================================================================}
 'LT6700CS6-1#TRPBF' | 'SMLF'    | 'IC'     | 'AL006700001'(!) = ''               | ''               | 'AL006700001' |'TSOT23-6_0-95_2-9X1-625'| 'IC OTHER(6P)LT6700CS6-1#TRPBF(TSOT-23)' | 'LIN'   | 'LT6700CS6-1#TRPBF' | 'EP'         | ''        | 'F0CE-GARY' | 'IC'  | ''      | 'LIN_LT6700CS6-1TRPBF.pdf' | ''            | ''     | ''  | ''      | ''     | ''  | ''      | ''      | ''     | '0 MILS'             | '0 MILS'            | '20210603'
 'LT6700CS6-1#TRPBF' | 'SMLF'    | 'EMPTY'  | 'AL006700001'(!) = ''               | ''               | 'AL006700001' |'TSOT23-6_0-95_2-9X1-625'| 'IC OTHER(6P)LT6700CS6-1#TRPBF(TSOT-23)' | 'LIN'   | 'LT6700CS6-1#TRPBF' | 'EP'         | ''        | 'F0CE-GARY' | 'IC'  | ''      | 'LIN_LT6700CS6-1TRPBF.pdf' | ''            | ''     | ''  | ''      | ''     | ''  | ''      | ''      | ''     | '0 MILS'             | '0 MILS'            | '20210603'

END_PART

END.

